(kicad_pcb
	(version 20241229)
	(generator "pcbnew")
	(generator_version "9.0")
	(general
		(thickness 1.294)
		(legacy_teardrops no)
	)
	(paper "A3")
	(title_block
		(title "Kintex 410T devboard")
		(date "2024-04-03")
		(rev "1.1.2")
		(comment 9 "footprints 206-211 of 975")
	)
	(layers
		(0 "F.Cu" mixed)
		(4 "In1.Cu" power)
		(6 "In2.Cu" power)
		(8 "In3.Cu" mixed)
		(10 "In4.Cu" power)
		(12 "In5.Cu" mixed)
		(14 "In6.Cu" power)
		(16 "In7.Cu" mixed)
		(18 "In8.Cu" power)
		(2 "B.Cu" mixed)
		(9 "F.Adhes" user "F.Adhesive")
		(11 "B.Adhes" user "B.Adhesive")
		(13 "F.Paste" user)
		(15 "B.Paste" user)
		(5 "F.SilkS" user "F.Silkscreen")
		(7 "B.SilkS" user "B.Silkscreen")
		(1 "F.Mask" user)
		(3 "B.Mask" user)
		(17 "Dwgs.User" user "User.Drawings")
		(19 "Cmts.User" user "User.Comments")
		(21 "Eco1.User" user "User.Eco1")
		(23 "Eco2.User" user "User.Eco2")
		(25 "Edge.Cuts" user)
		(27 "Margin" user)
		(31 "F.CrtYd" user "F.Courtyard")
		(29 "B.CrtYd" user "B.Courtyard")
		(35 "F.Fab" user)
		(33 "B.Fab" user)
	)
	(footprint "antmicro-footprints:C_0402_1005Metric"
		(layer "F.Cu")
		(at 196.1 165.149 180)
		(descr "Capacitor SMD 0402")
		(tags "capacitor SMD 0402")
		(property "Reference" "C342"
			(at -3.7 -0.301 0)
			(layer "F.SilkS")
			(effects
				(font
					(size 0.7 0.7)
					(thickness 0.15)
				)
				(justify right bottom)
			)
		)
		(property "Value" "C_470n_0402"
			(at 0 1.4 0)
			(layer "F.Fab")
			(effects
				(font
					(size 0.7 0.7)
					(thickness 0.15)
				)
				(justify right bottom)
			)
		)
		(property "Description" "SMD Multilayer Ceramic Capacitor, 0.47 µF, 25 V, 0402 [1005 Metric], ± 20%, X5R, C"
			(at 0 0 180)
			(layer "F.Fab")
			(hide yes)
			(effects
				(font
					(size 1.27 1.27)
					(thickness 0.15)
				)
			)
		)
		(property "Author" "Antmicro"
			(at 392.2 330.298 0)
			(layer "F.Fab")
			(hide yes)
			(effects
				(font
					(size 1 1)
					(thickness 0.15)
				)
			)
		)
		(property "Dielectric" ""
			(at 392.2 330.298 0)
			(layer "F.Fab")
			(hide yes)
			(effects
				(font
					(size 1 1)
					(thickness 0.15)
				)
			)
		)
		(property "License" "Apache-2.0"
			(at 392.2 330.298 0)
			(layer "F.Fab")
			(hide yes)
			(effects
				(font
					(size 1 1)
					(thickness 0.15)
				)
			)
		)
		(property "MPN" "C1005X5R1E474M050BB"
			(at 392.2 330.298 0)
			(layer "F.Fab")
			(hide yes)
			(effects
				(font
					(size 1 1)
					(thickness 0.15)
				)
			)
		)
		(property "Manufacturer" "TDK"
			(at 392.2 330.298 0)
			(layer "F.Fab")
			(hide yes)
			(effects
				(font
					(size 1 1)
					(thickness 0.15)
				)
			)
		)
		(property "Val" "470n"
			(at 392.2 330.298 0)
			(layer "F.Fab")
			(hide yes)
			(effects
				(font
					(size 1 1)
					(thickness 0.15)
				)
			)
		)
		(property "Voltage" ""
			(at 392.2 330.298 0)
			(layer "F.Fab")
			(hide yes)
			(effects
				(font
					(size 1 1)
					(thickness 0.15)
				)
			)
		)
		(sheetname "DC-DC Converters")
		(sheetfile "dc-dc.kicad_sch")
		(attr smd)
		(fp_rect
			(start -0.925 -0.47)
			(end 0.925 0.47)
			(stroke
				(width 0.05)
				(type default)
			)
			(fill no)
			(layer "F.CrtYd")
		)
		(fp_line
			(start 0.504 0.248)
			(end -0.494 0.248)
			(stroke
				(width 0.15)
				(type solid)
			)
			(layer "F.Fab")
		)
		(fp_line
			(start 0.504 -0.25)
			(end 0.504 0.248)
			(stroke
				(width 0.15)
				(type solid)
			)
			(layer "F.Fab")
		)
		(fp_line
			(start -0.494 0.248)
			(end -0.494 -0.25)
			(stroke
				(width 0.15)
				(type solid)
			)
			(layer "F.Fab")
		)
		(fp_line
			(start -0.494 -0.25)
			(end 0.504 -0.25)
			(stroke
				(width 0.15)
				(type solid)
			)
			(layer "F.Fab")
		)
		(pad "1" smd roundrect
			(at -0.48 0 180)
			(size 0.59 0.64)
			(layers "F.Cu" "F.Mask" "F.Paste")
			(roundrect_rratio 0.25)
			(net 1 "GND")
			(pintype "passive")
		)
		(pad "2" smd roundrect
			(at 0.48 0 180)
			(size 0.59 0.64)
			(layers "F.Cu" "F.Mask" "F.Paste")
			(roundrect_rratio 0.25)
			(net 741 "/DC-DC Converters/1V0_VCC")
			(pintype "passive")
		)
	)
	(footprint "antmicro-footprints:NetTie-2_SMD_Pad0.127mm"
		(layer "F.Cu")
		(at 249.3 143.602 90)
		(descr "Net tie, 2 pin, 0.127mm  SMD pads")
		(tags "net tie")
		(property "Reference" "NT4"
			(at -0.128 -1.345 90)
			(layer "F.SilkS")
			(hide yes)
			(effects
				(font
					(size 0.7 0.7)
					(thickness 0.15)
				)
				(justify left bottom)
			)
		)
		(property "Value" "Net-Tie_2"
			(at 0 1.199 90)
			(layer "F.Fab")
			(effects
				(font
					(size 0.7 0.7)
					(thickness 0.15)
				)
				(justify left bottom)
			)
		)
		(property "Description" "Net tie, 2 pins"
			(at 0 0 90)
			(layer "F.Fab")
			(hide yes)
			(effects
				(font
					(size 1.27 1.27)
					(thickness 0.15)
				)
			)
		)
		(property "Author" "Antmicro"
			(at 392.902 -105.698 0)
			(layer "F.Fab")
			(hide yes)
			(effects
				(font
					(size 1 1)
					(thickness 0.15)
				)
			)
		)
		(property "License" "Apache-2.0"
			(at 392.902 -105.698 0)
			(layer "F.Fab")
			(hide yes)
			(effects
				(font
					(size 1 1)
					(thickness 0.15)
				)
			)
		)
		(property "MPN" ""
			(at 392.902 -105.698 0)
			(layer "F.Fab")
			(hide yes)
			(effects
				(font
					(size 1 1)
					(thickness 0.15)
				)
			)
		)
		(property "Manufacturer" ""
			(at 392.902 -105.698 0)
			(layer "F.Fab")
			(hide yes)
			(effects
				(font
					(size 1 1)
					(thickness 0.15)
				)
			)
		)
		(sheetname "FPGA Config")
		(sheetfile "fpga-config.kicad_sch")
		(attr exclude_from_pos_files)
		(net_tie_pad_groups "1, 2")
		(fp_poly
			(pts
				(xy -0.0635 -0.0635) (xy 0.0625 -0.0635) (xy 0.0625 0.0635) (xy -0.0635 0.0635)
			)
			(stroke
				(width 0)
				(type solid)
			)
			(fill yes)
			(layer "F.Cu")
		)
		(pad "1" smd roundrect
			(at -0.127 0 270)
			(size 0.127 0.127)
			(layers "F.Cu")
			(roundrect_rratio 0.5)
			(chamfer_ratio 0)
			(chamfer top_left bottom_left)
			(net 1313 "/SUP_MCU.FPGA_M1")
			(pinfunction "1")
			(pintype "passive")
		)
		(pad "2" smd roundrect
			(at 0.126 0 90)
			(size 0.127 0.127)
			(layers "F.Cu")
			(roundrect_rratio 0.5)
			(chamfer_ratio 0)
			(chamfer top_left bottom_left)
			(net 299 "/FPGA Config/MODE1")
			(pinfunction "2")
			(pintype "passive")
		)
	)
	(footprint "antmicro-footprints:NetTie-2_SMD_Pad0.127mm"
		(layer "F.Cu")
		(at 258.12 120.04 90)
		(descr "Net tie, 2 pin, 0.127mm  SMD pads")
		(tags "net tie")
		(property "Reference" "NT26"
			(at -0.128 -1.345 90)
			(layer "F.SilkS")
			(hide yes)
			(effects
				(font
					(size 0.7 0.7)
					(thickness 0.15)
				)
				(justify left bottom)
			)
		)
		(property "Value" "Net-Tie_2"
			(at 0 1.199 90)
			(layer "F.Fab")
			(effects
				(font
					(size 0.7 0.7)
					(thickness 0.15)
				)
				(justify left bottom)
			)
		)
		(property "Description" "Net tie, 2 pins"
			(at 0 0 90)
			(layer "F.Fab")
			(hide yes)
			(effects
				(font
					(size 1.27 1.27)
					(thickness 0.15)
				)
			)
		)
		(property "Author" "Antmicro"
			(at 378.16 -138.08 0)
			(layer "F.Fab")
			(hide yes)
			(effects
				(font
					(size 1 1)
					(thickness 0.15)
				)
			)
		)
		(property "License" "Apache-2.0"
			(at 378.16 -138.08 0)
			(layer "F.Fab")
			(hide yes)
			(effects
				(font
					(size 1 1)
					(thickness 0.15)
				)
			)
		)
		(property "MPN" ""
			(at 378.16 -138.08 0)
			(layer "F.Fab")
			(hide yes)
			(effects
				(font
					(size 1 1)
					(thickness 0.15)
				)
			)
		)
		(property "Manufacturer" ""
			(at 378.16 -138.08 0)
			(layer "F.Fab")
			(hide yes)
			(effects
				(font
					(size 1 1)
					(thickness 0.15)
				)
			)
		)
		(sheetname "DC-DC Converters")
		(sheetfile "dc-dc.kicad_sch")
		(attr exclude_from_pos_files)
		(net_tie_pad_groups "1, 2")
		(fp_poly
			(pts
				(xy -0.0635 -0.0635) (xy 0.0625 -0.0635) (xy 0.0625 0.0635) (xy -0.0635 0.0635)
			)
			(stroke
				(width 0)
				(type solid)
			)
			(fill yes)
			(layer "F.Cu")
		)
		(pad "1" smd roundrect
			(at -0.127 0 270)
			(size 0.127 0.127)
			(layers "F.Cu")
			(roundrect_rratio 0.5)
			(chamfer_ratio 0)
			(chamfer top_left bottom_left)
			(net 1214 "/DC-DC Converters/SENSE_5V_P")
			(pinfunction "1")
			(pintype "passive")
		)
		(pad "2" smd roundrect
			(at 0.126 0 90)
			(size 0.127 0.127)
			(layers "F.Cu")
			(roundrect_rratio 0.5)
			(chamfer_ratio 0)
			(chamfer top_left bottom_left)
			(net 703 "+5V")
			(pinfunction "2")
			(pintype "passive")
		)
	)
	(footprint "antmicro-footprints:C_0402_1005Metric"
		(layer "F.Cu")
		(at 197.6 163.749 180)
		(descr "Capacitor SMD 0402")
		(tags "capacitor SMD 0402")
		(property "Reference" "C351"
			(at -5.95 -1.701 0)
			(layer "F.SilkS")
			(effects
				(font
					(size 0.7 0.7)
					(thickness 0.15)
				)
				(justify right bottom)
			)
		)
		(property "Value" "C_100n_0402"
			(at 0 1.4 0)
			(layer "F.Fab")
			(effects
				(font
					(size 0.7 0.7)
					(thickness 0.15)
				)
				(justify right bottom)
			)
		)
		(property "Description" "SMD Multilayer Ceramic Capacitor, 0.1 µF, 50 V, 0402 [1005 Metric], ± 10%, X5R, GRM Series"
			(at 0 0 180)
			(layer "F.Fab")
			(hide yes)
			(effects
				(font
					(size 1.27 1.27)
					(thickness 0.15)
				)
			)
		)
		(property "Author" "Antmicro"
			(at 395.2 327.498 0)
			(layer "F.Fab")
			(hide yes)
			(effects
				(font
					(size 1 1)
					(thickness 0.15)
				)
			)
		)
		(property "Dielectric" "X5R"
			(at 395.2 327.498 0)
			(layer "F.Fab")
			(hide yes)
			(effects
				(font
					(size 1 1)
					(thickness 0.15)
				)
			)
		)
		(property "License" "Apache-2.0"
			(at 395.2 327.498 0)
			(layer "F.Fab")
			(hide yes)
			(effects
				(font
					(size 1 1)
					(thickness 0.15)
				)
			)
		)
		(property "MPN" "GRM155R61H104KE14D"
			(at 395.2 327.498 0)
			(layer "F.Fab")
			(hide yes)
			(effects
				(font
					(size 1 1)
					(thickness 0.15)
				)
			)
		)
		(property "Manufacturer" "Murata"
			(at 395.2 327.498 0)
			(layer "F.Fab")
			(hide yes)
			(effects
				(font
					(size 1 1)
					(thickness 0.15)
				)
			)
		)
		(property "Val" "100n"
			(at 395.2 327.498 0)
			(layer "F.Fab")
			(hide yes)
			(effects
				(font
					(size 1 1)
					(thickness 0.15)
				)
			)
		)
		(property "Voltage" "50V"
			(at 395.2 327.498 0)
			(layer "F.Fab")
			(hide yes)
			(effects
				(font
					(size 1 1)
					(thickness 0.15)
				)
			)
		)
		(sheetname "DC-DC Converters")
		(sheetfile "dc-dc.kicad_sch")
		(attr smd)
		(fp_rect
			(start -0.925 -0.47)
			(end 0.925 0.47)
			(stroke
				(width 0.05)
				(type default)
			)
			(fill no)
			(layer "F.CrtYd")
		)
		(fp_line
			(start 0.504 0.248)
			(end -0.494 0.248)
			(stroke
				(width 0.15)
				(type solid)
			)
			(layer "F.Fab")
		)
		(fp_line
			(start 0.504 -0.25)
			(end 0.504 0.248)
			(stroke
				(width 0.15)
				(type solid)
			)
			(layer "F.Fab")
		)
		(fp_line
			(start -0.494 0.248)
			(end -0.494 -0.25)
			(stroke
				(width 0.15)
				(type solid)
			)
			(layer "F.Fab")
		)
		(fp_line
			(start -0.494 -0.25)
			(end 0.504 -0.25)
			(stroke
				(width 0.15)
				(type solid)
			)
			(layer "F.Fab")
		)
		(pad "1" smd roundrect
			(at -0.48 0 180)
			(size 0.59 0.64)
			(layers "F.Cu" "F.Mask" "F.Paste")
			(roundrect_rratio 0.25)
			(net 746 "/DC-DC Converters/1V0_SW")
			(pintype "passive")
		)
		(pad "2" smd roundrect
			(at 0.48 0 180)
			(size 0.59 0.64)
			(layers "F.Cu" "F.Mask" "F.Paste")
			(roundrect_rratio 0.25)
			(net 745 "/DC-DC Converters/1V0_BS")
			(pintype "passive")
		)
	)
	(footprint "antmicro-footprints:C_0402_1005Metric"
		(layer "F.Cu")
		(at 201.703752 98.9115)
		(descr "Capacitor SMD 0402")
		(tags "capacitor SMD 0402")
		(property "Reference" "C278"
			(at 4.296248 7.8885 0)
			(layer "F.SilkS")
			(effects
				(font
					(size 0.7 0.7)
					(thickness 0.15)
				)
				(justify left bottom)
			)
		)
		(property "Value" "C_22n_0402"
			(at 0 1.4 0)
			(layer "F.Fab")
			(effects
				(font
					(size 0.7 0.7)
					(thickness 0.15)
				)
				(justify left bottom)
			)
		)
		(property "Description" "SMD Multilayer Ceramic Capacitors, 0.022 µF, 50 V, 20%, 0402 [1005 Metric], X7R"
			(at 0 0 0)
			(layer "F.Fab")
			(hide yes)
			(effects
				(font
					(size 1.27 1.27)
					(thickness 0.15)
				)
			)
		)
		(property "Author" "Antmicro"
			(at 0 0 0)
			(layer "F.Fab")
			(hide yes)
			(effects
				(font
					(size 1 1)
					(thickness 0.15)
				)
			)
		)
		(property "Dielectric" ""
			(at 0 0 0)
			(layer "F.Fab")
			(hide yes)
			(effects
				(font
					(size 1 1)
					(thickness 0.15)
				)
			)
		)
		(property "License" "Apache-2.0"
			(at 0 0 0)
			(layer "F.Fab")
			(hide yes)
			(effects
				(font
					(size 1 1)
					(thickness 0.15)
				)
			)
		)
		(property "MPN" "GCM155R71H223MA55D"
			(at 0 0 0)
			(layer "F.Fab")
			(hide yes)
			(effects
				(font
					(size 1 1)
					(thickness 0.15)
				)
			)
		)
		(property "Manufacturer" "Murata"
			(at 0 0 0)
			(layer "F.Fab")
			(hide yes)
			(effects
				(font
					(size 1 1)
					(thickness 0.15)
				)
			)
		)
		(property "Val" "22n"
			(at 0 0 0)
			(layer "F.Fab")
			(hide yes)
			(effects
				(font
					(size 1 1)
					(thickness 0.15)
				)
			)
		)
		(property "Voltage" ""
			(at 0 0 0)
			(layer "F.Fab")
			(hide yes)
			(effects
				(font
					(size 1 1)
					(thickness 0.15)
				)
			)
		)
		(sheetname "HDMI + Ethernet")
		(sheetfile "hdmi-ethernet.kicad_sch")
		(attr smd)
		(fp_rect
			(start -0.925 -0.47)
			(end 0.925 0.47)
			(stroke
				(width 0.05)
				(type default)
			)
			(fill no)
			(layer "F.CrtYd")
		)
		(fp_line
			(start -0.494 -0.25)
			(end 0.504 -0.25)
			(stroke
				(width 0.15)
				(type solid)
			)
			(layer "F.Fab")
		)
		(fp_line
			(start -0.494 0.248)
			(end -0.494 -0.25)
			(stroke
				(width 0.15)
				(type solid)
			)
			(layer "F.Fab")
		)
		(fp_line
			(start 0.504 -0.25)
			(end 0.504 0.248)
			(stroke
				(width 0.15)
				(type solid)
			)
			(layer "F.Fab")
		)
		(fp_line
			(start 0.504 0.248)
			(end -0.494 0.248)
			(stroke
				(width 0.15)
				(type solid)
			)
			(layer "F.Fab")
		)
		(pad "1" smd roundrect
			(at -0.48 0)
			(size 0.59 0.64)
			(layers "F.Cu" "F.Mask" "F.Paste")
			(roundrect_rratio 0.25)
			(net 1 "GND")
			(pintype "passive")
		)
		(pad "2" smd roundrect
			(at 0.48 0)
			(size 0.59 0.64)
			(layers "F.Cu" "F.Mask" "F.Paste")
			(roundrect_rratio 0.25)
			(net 728 "/HDMI + Ethernet/GBE_AVDDL{slash}PLL")
			(pintype "passive")
		)
	)
	(footprint "antmicro-footprints:R_0402_1005Metric"
		(layer "F.Cu")
		(at 216.45 157.1 -90)
		(descr "Resistor SMD 0402")
		(tags "resistor SMD 0402")
		(property "Reference" "R82"
			(at -0.75 -0.4 270)
			(layer "F.SilkS")
			(effects
				(font
					(size 0.7 0.7)
					(thickness 0.15)
				)
				(justify left bottom)
			)
		)
		(property "Value" "R_0R_0402"
			(at 0 1.4 270)
			(layer "F.Fab")
			(effects
				(font
					(size 0.7 0.7)
					(thickness 0.15)
				)
				(justify left bottom)
			)
		)
		(property "Description" "SMD Chip Resistor, Jumper, 0 ohm, 100 mW, 0402 [1005 Metric], Thick Film, General Purpose"
			(at 0 0 270)
			(layer "F.Fab")
			(hide yes)
			(effects
				(font
					(size 1.27 1.27)
					(thickness 0.15)
				)
			)
		)
		(property "Author" "Antmicro"
			(at 59.35 373.55 0)
			(layer "F.Fab")
			(hide yes)
			(effects
				(font
					(size 1 1)
					(thickness 0.15)
				)
			)
		)
		(property "Current" "1A"
			(at 59.35 373.55 0)
			(layer "F.Fab")
			(hide yes)
			(effects
				(font
					(size 1 1)
					(thickness 0.15)
				)
			)
		)
		(property "License" "Apache-2.0"
			(at 59.35 373.55 0)
			(layer "F.Fab")
			(hide yes)
			(effects
				(font
					(size 1 1)
					(thickness 0.15)
				)
			)
		)
		(property "MPN" "ERJ2GE0R00X"
			(at 59.35 373.55 0)
			(layer "F.Fab")
			(hide yes)
			(effects
				(font
					(size 1 1)
					(thickness 0.15)
				)
			)
		)
		(property "Manufacturer" "Panasonic"
			(at 59.35 373.55 0)
			(layer "F.Fab")
			(hide yes)
			(effects
				(font
					(size 1 1)
					(thickness 0.15)
				)
			)
		)
		(property "Tolerance" ""
			(at 59.35 373.55 0)
			(layer "F.Fab")
			(hide yes)
			(effects
				(font
					(size 1 1)
					(thickness 0.15)
				)
			)
		)
		(property "Val" "0R"
			(at 59.35 373.55 0)
			(layer "F.Fab")
			(hide yes)
			(effects
				(font
					(size 1 1)
					(thickness 0.15)
				)
			)
		)
		(sheetname "SPI Flash + SD Card")
		(sheetfile "spi-flash.kicad_sch")
		(attr smd)
		(fp_rect
			(start -0.925 -0.47)
			(end 0.925 0.47)
			(stroke
				(width 0.05)
				(type default)
			)
			(fill no)
			(layer "F.CrtYd")
		)
		(fp_rect
			(start -0.5 -0.25)
			(end 0.5 0.25)
			(stroke
				(width 0.15)
				(type solid)
			)
			(fill no)
			(layer "F.Fab")
		)
		(pad "1" smd roundrect
			(at -0.48 0 270)
			(size 0.59 0.64)
			(layers "F.Cu" "F.Mask" "F.Paste")
			(roundrect_rratio 0.25)
			(net 410 "/FPGA Bank 33 & 34/USR_FLASH_0.DQ0")
			(pintype "passive")
		)
		(pad "2" smd roundrect
			(at 0.48 0 270)
			(size 0.59 0.64)
			(layers "F.Cu" "F.Mask" "F.Paste")
			(roundrect_rratio 0.25)
			(net 902 "/SPI Flash + SD Card/USR_FLASH_0_DQ0")
			(pintype "passive")
		)
	)
)
